(kicad_pcb
	(version 20260206)
	(generator "pcbnew")
	(generator_version "10.0")
	(general
		(thickness 1.6)
		(legacy_teardrops no)
	)
	(paper "A4")
	(title_block
		(title "Bryce Canyon_IOM_M2_16342-2_OCP.brd")
		(comment 1 "Bryce Canyon / footprints 35-41 of 1146")
	)
	(layers
		(0 "F.Cu" signal "TOP")
		(4 "In1.Cu" signal "L2GND")
		(6 "In2.Cu" signal "L3")
		(8 "In3.Cu" signal "L4VCC")
		(10 "In4.Cu" signal "L5VCC")
		(12 "In5.Cu" signal "L6")
		(14 "In6.Cu" signal "L7GND")
		(2 "B.Cu" signal "BOTTOM")
		(9 "F.Adhes" user "F.Adhesive")
		(11 "B.Adhes" user "B.Adhesive")
		(13 "F.Paste" user "Package Geometry/Pastemask Top")
		(15 "B.Paste" user "Package Geometry/Pastemask Bottom")
		(5 "F.SilkS" user "Ref Des/Silkscreen Top")
		(7 "B.SilkS" user "Ref Des/Silkscreen Bottom")
		(1 "F.Mask" user "Board Geometry/Soldermask Top")
		(3 "B.Mask" user "Board Geometry/Soldermask Bottom")
		(17 "Dwgs.User" user "User.Drawings")
		(19 "Cmts.User" user "User.Comments")
		(21 "Eco1.User" user "User.Eco1")
		(23 "Eco2.User" user "User.Eco2")
		(25 "Edge.Cuts" user "Board Geometry/Outline")
		(27 "Margin" user)
		(31 "F.CrtYd" user "Package Geometry/Place Bound Top")
		(29 "B.CrtYd" user "Package Geometry/Place Bound Bottom")
		(35 "F.Fab" user "Ref Des/Assembly Top")
		(33 "B.Fab" user "Ref Des/Assembly Bottom")
	)
	(footprint ""
		(layer "F.Cu")
		(at 27.419046 -154.422856 -90)
		(property "Reference" "R770"
			(at 0 0 270)
			(layer "F.SilkS")
			(hide yes)
			(effects
				(font
					(size 1.27 1.27)
				)
			)
		)
		(property "Value" "0R2J-2-GP"
			(at 0.064008 -3.993896 270)
			(unlocked yes)
			(layer "F.Fab")
			(hide yes)
			(effects
				(font
					(size 1.016 1.016)
					(thickness 0.1524)
				)
			)
		)
		(property "Device Type" "R402H16"
			(at 0.064008 -5.517896 270)
			(unlocked yes)
			(layer "F.Fab")
			(hide yes)
			(effects
				(font
					(size 1.016 1.016)
					(thickness 0.1524)
				)
			)
		)
		(duplicate_pad_numbers_are_jumpers no)
		(fp_line
			(start -0.508 -0.9398)
			(end -0.508 0.9398)
			(stroke
				(width 0.1524)
				(type default)
			)
			(layer "F.SilkS")
		)
		(fp_line
			(start 0.508 -0.9398)
			(end -0.508 -0.9398)
			(stroke
				(width 0.1524)
				(type default)
			)
			(layer "F.SilkS")
		)
		(fp_rect
			(start -0.508 0.9398)
			(end 0.508 -0.9398)
			(stroke
				(width 0)
				(type default)
			)
			(fill no)
			(layer "F.CrtYd")
		)
		(fp_rect
			(start -0.508 0.9398)
			(end 0.508 -0.9398)
			(stroke
				(width 0)
				(type default)
			)
			(fill no)
			(layer "F.Fab")
		)
		(pad "1" smd custom
			(at 0 -0.4445 270)
			(size 0.1397 0.1397)
			(layers "F.Cu" "F.Mask" "F.Paste")
			(net "DEBUG_GPIO_BMC_R_3")
			(options
				(clearance outline)
				(anchor circle)
			)
			(primitives
				(gr_poly
					(pts
						(arc
							(start -0.1778 -0.2794)
							(mid -0.249642 -0.249642)
							(end -0.2794 -0.1778)
						)
						(arc
							(start -0.2794 0.1778)
							(mid -0.249642 0.249642)
							(end -0.1778 0.2794)
						)
						(arc
							(start 0.1778 0.2794)
							(mid 0.249642 0.249642)
							(end 0.2794 0.1778)
						)
						(arc
							(start 0.2794 -0.1778)
							(mid 0.249642 -0.249642)
							(end 0.1778 -0.2794)
						)
					)
					(width 0)
					(fill yes)
				)
			)
		)
		(pad "2" smd custom
			(at 0 0.4445 270)
			(size 0.1397 0.1397)
			(layers "F.Cu" "F.Mask" "F.Paste")
			(net "DEBUG_GPIO_BMC_3")
			(options
				(clearance outline)
				(anchor circle)
			)
			(primitives
				(gr_poly
					(pts
						(arc
							(start -0.1778 -0.2794)
							(mid -0.249642 -0.249642)
							(end -0.2794 -0.1778)
						)
						(arc
							(start -0.2794 0.1778)
							(mid -0.249642 0.249642)
							(end -0.1778 0.2794)
						)
						(arc
							(start 0.1778 0.2794)
							(mid 0.249642 0.249642)
							(end 0.2794 0.1778)
						)
						(arc
							(start 0.2794 -0.1778)
							(mid 0.249642 -0.249642)
							(end 0.1778 -0.2794)
						)
					)
					(width 0)
					(fill yes)
				)
			)
		)
	)
	(footprint ""
		(layer "F.Cu")
		(at 69.883782 -156.277818 180)
		(property "Reference" "X2"
			(at 0 0 180)
			(layer "F.SilkS")
			(hide yes)
			(effects
				(font
					(size 1.27 1.27)
				)
			)
		)
		(property "Value" "OSC-50MHZ-16-GP"
			(at 0.0127 -2.7686 180)
			(unlocked yes)
			(layer "F.Fab")
			(hide yes)
			(effects
				(font
					(size 1.016 1.016)
					(thickness 0.1524)
				)
			)
		)
		(property "Device Type" "OSC-3225-4P-3H48"
			(at 0.0127 -4.2926 180)
			(unlocked yes)
			(layer "F.Fab")
			(hide yes)
			(effects
				(font
					(size 1.016 1.016)
					(thickness 0.1524)
				)
			)
		)
		(duplicate_pad_numbers_are_jumpers no)
		(fp_line
			(start 2.1209 1.5367)
			(end -2.1209 1.5367)
			(stroke
				(width 0.1524)
				(type default)
			)
			(layer "F.SilkS")
		)
		(fp_line
			(start 2.1209 -1.5367)
			(end 2.1209 1.5367)
			(stroke
				(width 0.1524)
				(type default)
			)
			(layer "F.SilkS")
		)
		(fp_line
			(start -1.3208 1.6256)
			(end -2.2352 1.6256)
			(stroke
				(width 0.3302)
				(type default)
			)
			(layer "F.SilkS")
		)
		(fp_line
			(start -2.1209 1.5367)
			(end -2.1209 -1.5367)
			(stroke
				(width 0.1524)
				(type default)
			)
			(layer "F.SilkS")
		)
		(fp_line
			(start -2.1209 -1.5367)
			(end 2.1209 -1.5367)
			(stroke
				(width 0.1524)
				(type default)
			)
			(layer "F.SilkS")
		)
		(fp_line
			(start -2.2352 1.6256)
			(end -2.2352 0.635)
			(stroke
				(width 0.3302)
				(type default)
			)
			(layer "F.SilkS")
		)
		(fp_poly
			(pts
				(xy -0.982218 2.599182) (xy -2.252218 2.599182) (xy -1.617218 1.964182)
			)
			(stroke
				(width 0)
				(type default)
			)
			(fill yes)
			(layer "F.SilkS")
		)
		(fp_rect
			(start -1.6002 1.2446)
			(end 1.6002 -1.2446)
			(stroke
				(width 0)
				(type default)
			)
			(fill no)
			(layer "F.CrtYd")
		)
		(fp_poly
			(pts
				(xy -2.3749 1.7907) (xy -2.3749 -1.7907) (xy 2.3749 -1.7907) (xy 2.3749 1.7907) (xy 1.6002 1.7907)
				(xy 1.6002 -1.2446) (xy -1.6002 -1.2446) (xy -1.6002 1.2446) (xy 1.59512 1.2446) (xy 1.59512 1.7907)
			)
			(stroke
				(width 0)
				(type default)
			)
			(fill no)
			(layer "F.CrtYd")
		)
		(fp_rect
			(start -2.3749 1.7907)
			(end 2.3749 -1.7907)
			(stroke
				(width 0)
				(type default)
			)
			(fill no)
			(layer "F.Fab")
		)
		(pad "1" smd rect
			(at -1.171448 0.824992 180)
			(size 1.397 0.9144)
			(layers "F.Cu" "F.Mask" "F.Paste")
			(net "FM_OSC_50M_EN")
		)
		(pad "2" smd rect
			(at 1.171448 0.824992 180)
			(size 1.397 0.9144)
			(layers "F.Cu" "F.Mask" "F.Paste")
			(net "GND")
		)
		(pad "3" smd rect
			(at 1.171448 -0.824992 180)
			(size 1.397 0.9144)
			(layers "F.Cu" "F.Mask" "F.Paste")
			(net "50M_CLK_OUT")
		)
		(pad "4" smd rect
			(at -1.171448 -0.824992 180)
			(size 1.397 0.9144)
			(layers "F.Cu" "F.Mask" "F.Paste")
			(net "P3V3_STBY")
		)
		(zone
			(layer "F.Cu")
			(hatch none 0.5)
			(connect_pads
				(clearance 0)
			)
			(min_thickness 0.25)
			(keepout
				(tracks not_allowed)
				(vias allowed)
				(pads allowed)
				(copperpour not_allowed)
				(footprints allowed)
			)
			(placement
				(enabled no)
				(sheetname "")
			)
			(fill
				(thermal_gap 0.5)
				(thermal_bridge_width 0.5)
				(island_removal_mode 0)
			)
			(polygon
				(pts
					(xy 70.03161 -156.32049) (xy 69.735954 -156.32049) (xy 69.735954 -156.235146) (xy 70.03161 -156.235146)
				)
			)
		)
		(zone
			(layer "F.Cu")
			(hatch none 0.5)
			(connect_pads
				(clearance 0)
			)
			(min_thickness 0.25)
			(keepout
				(tracks allowed)
				(vias not_allowed)
				(pads allowed)
				(copperpour not_allowed)
				(footprints allowed)
			)
			(placement
				(enabled no)
				(sheetname "")
			)
			(fill
				(thermal_gap 0.5)
				(thermal_bridge_width 0.5)
				(island_removal_mode 0)
			)
			(polygon
				(pts
					(xy 70.35673 -157.56001) (xy 70.35673 -156.64561) (xy 71.75373 -156.64561) (xy 71.75373 -155.910026)
					(xy 70.35673 -155.910026) (xy 70.35673 -154.995626) (xy 69.410834 -154.995626) (xy 69.410834 -155.910026)
					(xy 68.013834 -155.910026) (xy 68.013834 -156.64561) (xy 69.410834 -156.64561) (xy 69.410834 -157.56001)
				)
			)
		)
	)
	(footprint ""
		(layer "F.Cu")
		(at 68.4276 -153.8732 -90)
		(property "Reference" "R306"
			(at 0 0 270)
			(layer "F.SilkS")
			(hide yes)
			(effects
				(font
					(size 1.27 1.27)
				)
			)
		)
		(property "Value" "33R2J-2-GP"
			(at 0.064008 -3.993896 270)
			(unlocked yes)
			(layer "F.Fab")
			(hide yes)
			(effects
				(font
					(size 1.016 1.016)
					(thickness 0.1524)
				)
			)
		)
		(property "Device Type" "R402H16"
			(at 0.064008 -5.517896 270)
			(unlocked yes)
			(layer "F.Fab")
			(hide yes)
			(effects
				(font
					(size 1.016 1.016)
					(thickness 0.1524)
				)
			)
		)
		(duplicate_pad_numbers_are_jumpers no)
		(fp_line
			(start -0.508 -0.9398)
			(end -0.508 0.9398)
			(stroke
				(width 0.1524)
				(type default)
			)
			(layer "F.SilkS")
		)
		(fp_line
			(start 0.508 -0.9398)
			(end -0.508 -0.9398)
			(stroke
				(width 0.1524)
				(type default)
			)
			(layer "F.SilkS")
		)
		(fp_rect
			(start -0.508 0.9398)
			(end 0.508 -0.9398)
			(stroke
				(width 0)
				(type default)
			)
			(fill no)
			(layer "F.CrtYd")
		)
		(fp_rect
			(start -0.508 0.9398)
			(end 0.508 -0.9398)
			(stroke
				(width 0)
				(type default)
			)
			(fill no)
			(layer "F.Fab")
		)
		(pad "1" smd custom
			(at 0 -0.4445 270)
			(size 0.1397 0.1397)
			(layers "F.Cu" "F.Mask" "F.Paste")
			(net "50M_CLK_OUT")
			(options
				(clearance outline)
				(anchor circle)
			)
			(primitives
				(gr_poly
					(pts
						(arc
							(start -0.1778 -0.2794)
							(mid -0.249642 -0.249642)
							(end -0.2794 -0.1778)
						)
						(arc
							(start -0.2794 0.1778)
							(mid -0.249642 0.249642)
							(end -0.1778 0.2794)
						)
						(arc
							(start 0.1778 0.2794)
							(mid 0.249642 0.249642)
							(end 0.2794 0.1778)
						)
						(arc
							(start 0.2794 -0.1778)
							(mid 0.249642 -0.249642)
							(end 0.1778 -0.2794)
						)
					)
					(width 0)
					(fill yes)
				)
			)
		)
		(pad "2" smd custom
			(at 0 0.4445 270)
			(size 0.1397 0.1397)
			(layers "F.Cu" "F.Mask" "F.Paste")
			(net "50M_CLK_OUT_R")
			(options
				(clearance outline)
				(anchor circle)
			)
			(primitives
				(gr_poly
					(pts
						(arc
							(start -0.1778 -0.2794)
							(mid -0.249642 -0.249642)
							(end -0.2794 -0.1778)
						)
						(arc
							(start -0.2794 0.1778)
							(mid -0.249642 0.249642)
							(end -0.1778 0.2794)
						)
						(arc
							(start 0.1778 0.2794)
							(mid 0.249642 0.249642)
							(end 0.2794 0.1778)
						)
						(arc
							(start 0.2794 -0.1778)
							(mid 0.249642 -0.249642)
							(end 0.1778 -0.2794)
						)
					)
					(width 0)
					(fill yes)
				)
			)
		)
	)
	(footprint ""
		(layer "F.Cu")
		(at 23.058882 -173.234096 90)
		(property "Reference" "C231"
			(at 0 0 90)
			(layer "F.SilkS")
			(hide yes)
			(effects
				(font
					(size 1.27 1.27)
				)
			)
		)
		(property "Value" "SC10U6D3V5KX-4GP"
			(at -0.0762 -6.1214 90)
			(unlocked yes)
			(layer "F.Fab")
			(hide yes)
			(effects
				(font
					(size 1.016 1.016)
					(thickness 0.1524)
				)
			)
		)
		(property "Device Type" "C805H58"
			(at -0.0762 -8.1534 90)
			(unlocked yes)
			(layer "F.Fab")
			(hide yes)
			(effects
				(font
					(size 1.016 1.016)
					(thickness 0.1524)
				)
			)
		)
		(duplicate_pad_numbers_are_jumpers no)
		(fp_line
			(start 0.635 0)
			(end -0.635 0)
			(stroke
				(width 0.508)
				(type default)
			)
			(layer "F.SilkS")
		)
		(fp_rect
			(start -0.9652 1.778)
			(end 0.9652 -1.778)
			(stroke
				(width 0)
				(type default)
			)
			(fill no)
			(layer "F.CrtYd")
		)
		(fp_poly
			(pts
				(xy -0.9652 -1.778) (xy 0.9652 -1.778) (xy 0.9652 1.778) (xy -0.9652 1.778)
			)
			(stroke
				(width 0)
				(type default)
			)
			(fill no)
			(layer "F.Fab")
		)
		(pad "1" smd rect
			(at 0 -0.9652 90)
			(size 1.397 1.143)
			(layers "F.Cu" "F.Mask" "F.Paste")
			(net "P1V8_STBY")
		)
		(pad "2" smd rect
			(at 0 0.9652 90)
			(size 1.397 1.143)
			(layers "F.Cu" "F.Mask" "F.Paste")
			(net "GND")
		)
	)
	(footprint ""
		(layer "F.Cu")
		(at 73.9902 -140.0302 -90)
		(property "Reference" "R58"
			(at 0 0 270)
			(layer "F.SilkS")
			(hide yes)
			(effects
				(font
					(size 1.27 1.27)
				)
			)
		)
		(property "Value" "33R2F-3-GP"
			(at 0.064008 -3.993896 270)
			(unlocked yes)
			(layer "F.Fab")
			(hide yes)
			(effects
				(font
					(size 1.016 1.016)
					(thickness 0.1524)
				)
			)
		)
		(property "Device Type" "R402H16"
			(at 0.064008 -5.517896 270)
			(unlocked yes)
			(layer "F.Fab")
			(hide yes)
			(effects
				(font
					(size 1.016 1.016)
					(thickness 0.1524)
				)
			)
		)
		(duplicate_pad_numbers_are_jumpers no)
		(fp_line
			(start -0.508 -0.9398)
			(end -0.508 0.9398)
			(stroke
				(width 0.1524)
				(type default)
			)
			(layer "F.SilkS")
		)
		(fp_line
			(start 0.508 -0.9398)
			(end -0.508 -0.9398)
			(stroke
				(width 0.1524)
				(type default)
			)
			(layer "F.SilkS")
		)
		(fp_rect
			(start -0.508 0.9398)
			(end 0.508 -0.9398)
			(stroke
				(width 0)
				(type default)
			)
			(fill no)
			(layer "F.CrtYd")
		)
		(fp_rect
			(start -0.508 0.9398)
			(end 0.508 -0.9398)
			(stroke
				(width 0)
				(type default)
			)
			(fill no)
			(layer "F.Fab")
		)
		(pad "1" smd custom
			(at 0 -0.4445 270)
			(size 0.1397 0.1397)
			(layers "F.Cu" "F.Mask" "F.Paste")
			(net "SYS_RST_BTN_IN_N")
			(options
				(clearance outline)
				(anchor circle)
			)
			(primitives
				(gr_poly
					(pts
						(arc
							(start -0.1778 -0.2794)
							(mid -0.249642 -0.249642)
							(end -0.2794 -0.1778)
						)
						(arc
							(start -0.2794 0.1778)
							(mid -0.249642 0.249642)
							(end -0.1778 0.2794)
						)
						(arc
							(start 0.1778 0.2794)
							(mid 0.249642 0.249642)
							(end 0.2794 0.1778)
						)
						(arc
							(start 0.2794 -0.1778)
							(mid 0.249642 -0.249642)
							(end 0.1778 -0.2794)
						)
					)
					(width 0)
					(fill yes)
				)
			)
		)
		(pad "2" smd custom
			(at 0 0.4445 270)
			(size 0.1397 0.1397)
			(layers "F.Cu" "F.Mask" "F.Paste")
			(net "FP_RESET_RC_N")
			(options
				(clearance outline)
				(anchor circle)
			)
			(primitives
				(gr_poly
					(pts
						(arc
							(start -0.1778 -0.2794)
							(mid -0.249642 -0.249642)
							(end -0.2794 -0.1778)
						)
						(arc
							(start -0.2794 0.1778)
							(mid -0.249642 0.249642)
							(end -0.1778 0.2794)
						)
						(arc
							(start 0.1778 0.2794)
							(mid 0.249642 0.249642)
							(end 0.2794 0.1778)
						)
						(arc
							(start 0.2794 -0.1778)
							(mid 0.249642 -0.249642)
							(end 0.1778 -0.2794)
						)
					)
					(width 0)
					(fill yes)
				)
			)
		)
	)
	(footprint ""
		(layer "F.Cu")
		(at 215.17864 -100.583492 90)
		(property "Reference" "R842"
			(at 0 0 90)
			(layer "F.SilkS")
			(hide yes)
			(effects
				(font
					(size 1.27 1.27)
				)
			)
		)
		(property "Value" "309KR2F-GP"
			(at 0.064008 -3.993896 90)
			(unlocked yes)
			(layer "F.Fab")
			(hide yes)
			(effects
				(font
					(size 1.016 1.016)
					(thickness 0.1524)
				)
			)
		)
		(property "Device Type" "R402H16"
			(at 0.064008 -5.517896 90)
			(unlocked yes)
			(layer "F.Fab")
			(hide yes)
			(effects
				(font
					(size 1.016 1.016)
					(thickness 0.1524)
				)
			)
		)
		(duplicate_pad_numbers_are_jumpers no)
		(fp_line
			(start 0.508 -0.9398)
			(end -0.508 -0.9398)
			(stroke
				(width 0.1524)
				(type default)
			)
			(layer "F.SilkS")
		)
		(fp_line
			(start -0.508 -0.9398)
			(end -0.508 0.9398)
			(stroke
				(width 0.1524)
				(type default)
			)
			(layer "F.SilkS")
		)
		(fp_rect
			(start -0.508 0.9398)
			(end 0.508 -0.9398)
			(stroke
				(width 0)
				(type default)
			)
			(fill no)
			(layer "F.CrtYd")
		)
		(fp_rect
			(start -0.508 0.9398)
			(end 0.508 -0.9398)
			(stroke
				(width 0)
				(type default)
			)
			(fill no)
			(layer "F.Fab")
		)
		(pad "1" smd custom
			(at 0 -0.4445 90)
			(size 0.1397 0.1397)
			(layers "F.Cu" "F.Mask" "F.Paste")
			(net "AGND_P3V3_M2")
			(options
				(clearance outline)
				(anchor circle)
			)
			(primitives
				(gr_poly
					(pts
						(arc
							(start -0.1778 -0.2794)
							(mid -0.249642 -0.249642)
							(end -0.2794 -0.1778)
						)
						(arc
							(start -0.2794 0.1778)
							(mid -0.249642 0.249642)
							(end -0.1778 0.2794)
						)
						(arc
							(start 0.1778 0.2794)
							(mid 0.249642 0.249642)
							(end 0.2794 0.1778)
						)
						(arc
							(start 0.2794 -0.1778)
							(mid 0.249642 -0.249642)
							(end 0.1778 -0.2794)
						)
					)
					(width 0)
					(fill yes)
				)
			)
		)
		(pad "2" smd custom
			(at 0 0.4445 90)
			(size 0.1397 0.1397)
			(layers "F.Cu" "F.Mask" "F.Paste")
			(net "P3V3_M2_RF")
			(options
				(clearance outline)
				(anchor circle)
			)
			(primitives
				(gr_poly
					(pts
						(arc
							(start -0.1778 -0.2794)
							(mid -0.249642 -0.249642)
							(end -0.2794 -0.1778)
						)
						(arc
							(start -0.2794 0.1778)
							(mid -0.249642 0.249642)
							(end -0.1778 0.2794)
						)
						(arc
							(start 0.1778 0.2794)
							(mid 0.249642 0.249642)
							(end 0.2794 0.1778)
						)
						(arc
							(start 0.2794 -0.1778)
							(mid 0.249642 -0.249642)
							(end 0.1778 -0.2794)
						)
					)
					(width 0)
					(fill yes)
				)
			)
		)
	)
	(footprint ""
		(layer "F.Cu")
		(at 69.51726 -183.78678 -90)
		(property "Reference" "R510"
			(at 0 0 270)
			(layer "F.SilkS")
			(hide yes)
			(effects
				(font
					(size 1.27 1.27)
				)
			)
		)
		(property "Value" "0R2J-2-GP"
			(at 0.064008 -3.993896 270)
			(unlocked yes)
			(layer "F.Fab")
			(hide yes)
			(effects
				(font
					(size 1.016 1.016)
					(thickness 0.1524)
				)
			)
		)
		(property "Device Type" "R402H16"
			(at 0.064008 -5.517896 270)
			(unlocked yes)
			(layer "F.Fab")
			(hide yes)
			(effects
				(font
					(size 1.016 1.016)
					(thickness 0.1524)
				)
			)
		)
		(duplicate_pad_numbers_are_jumpers no)
		(fp_line
			(start -0.508 -0.9398)
			(end -0.508 0.9398)
			(stroke
				(width 0.1524)
				(type default)
			)
			(layer "F.SilkS")
		)
		(fp_line
			(start 0.508 -0.9398)
			(end -0.508 -0.9398)
			(stroke
				(width 0.1524)
				(type default)
			)
			(layer "F.SilkS")
		)
		(fp_rect
			(start -0.508 0.9398)
			(end 0.508 -0.9398)
			(stroke
				(width 0)
				(type default)
			)
			(fill no)
			(layer "F.CrtYd")
		)
		(fp_rect
			(start -0.508 0.9398)
			(end 0.508 -0.9398)
			(stroke
				(width 0)
				(type default)
			)
			(fill no)
			(layer "F.Fab")
		)
		(pad "1" smd custom
			(at 0 -0.4445 270)
			(size 0.1397 0.1397)
			(layers "F.Cu" "F.Mask" "F.Paste")
			(net "TPS74801_P2V5_STBY_EN")
			(options
				(clearance outline)
				(anchor circle)
			)
			(primitives
				(gr_poly
					(pts
						(arc
							(start -0.1778 -0.2794)
							(mid -0.249642 -0.249642)
							(end -0.2794 -0.1778)
						)
						(arc
							(start -0.2794 0.1778)
							(mid -0.249642 0.249642)
							(end -0.1778 0.2794)
						)
						(arc
							(start 0.1778 0.2794)
							(mid 0.249642 0.249642)
							(end 0.2794 0.1778)
						)
						(arc
							(start 0.2794 -0.1778)
							(mid 0.249642 -0.249642)
							(end 0.1778 -0.2794)
						)
					)
					(width 0)
					(fill yes)
				)
			)
		)
		(pad "2" smd custom
			(at 0 0.4445 270)
			(size 0.1397 0.1397)
			(layers "F.Cu" "F.Mask" "F.Paste")
			(net "PWRGD_P3V3_STBY")
			(options
				(clearance outline)
				(anchor circle)
			)
			(primitives
				(gr_poly
					(pts
						(arc
							(start -0.1778 -0.2794)
							(mid -0.249642 -0.249642)
							(end -0.2794 -0.1778)
						)
						(arc
							(start -0.2794 0.1778)
							(mid -0.249642 0.249642)
							(end -0.1778 0.2794)
						)
						(arc
							(start 0.1778 0.2794)
							(mid 0.249642 0.249642)
							(end 0.2794 0.1778)
						)
						(arc
							(start 0.2794 -0.1778)
							(mid 0.249642 -0.249642)
							(end 0.1778 -0.2794)
						)
					)
					(width 0)
					(fill yes)
				)
			)
		)
	)
)
